# BASEBOARD_FAB2 (Tioga Pass) — schematic netlist excerpt (pin names and nets, part order shuffled) for the footprints in the layout excerpt that follows; sources: Cadence DE-HDL packaged netlist, KiCad conversion of Wiwynn_Tioga_Pass_MB.brd

R2M8  RES  1.5K 1% CHIP  pkg 0402  page 133 : A = P3V3_STBY ; B = FM_CPU0_RC_ERROR_N
CT71  CAP  1000PF 50V 10% X7R  pkg 0402LF  page 212 : A = A_TSENSE_PVCCIO_CPU0 ; B = GND
R1D48  RES  10.0 1% CHIP  pkg 0402  page 200 : A = A_HSC_GATE ; B = A_HSC_GATE3_R

(kicad_pcb
	(version 20260206)
	(generator "pcbnew")
	(generator_version "10.0")
	(general
		(thickness 1.6)
		(legacy_teardrops no)
	)
	(paper "A4")
	(title_block
		(title "Wiwynn_Tioga_Pass_MB.brd")
		(comment 1 "Tioga Pass / footprints 2168-2170 of 4770")
	)
	(layers
		(0 "F.Cu" signal "TOP")
		(4 "In1.Cu" signal "L2GND")
		(6 "In2.Cu" signal "L3")
		(8 "In3.Cu" signal "L4GND")
		(10 "In4.Cu" signal "L5")
		(12 "In5.Cu" signal "L6GND")
		(14 "In6.Cu" signal "L7VCC")
		(16 "In7.Cu" signal "L8VCC")
		(18 "In8.Cu" signal "L9GND")
		(20 "In9.Cu" signal "L10")
		(22 "In10.Cu" signal "L11GND")
		(24 "In11.Cu" signal "L12")
		(26 "In12.Cu" signal "L13GND")
		(2 "B.Cu" signal "BOTTOM")
		(9 "F.Adhes" user "F.Adhesive")
		(11 "B.Adhes" user "B.Adhesive")
		(13 "F.Paste" user "Package Geometry/Pastemask Top")
		(15 "B.Paste" user "Package Geometry/Pastemask Bottom")
		(5 "F.SilkS" user "Ref Des/Silkscreen Top")
		(7 "B.SilkS" user "Ref Des/Silkscreen Bottom")
		(1 "F.Mask" user "Board Geometry/Soldermask Top")
		(3 "B.Mask" user "Board Geometry/Soldermask Bottom")
		(17 "Dwgs.User" user "User.Drawings")
		(19 "Cmts.User" user "User.Comments")
		(21 "Eco1.User" user "User.Eco1")
		(23 "Eco2.User" user "User.Eco2")
		(25 "Edge.Cuts" user "Board Geometry/Outline")
		(27 "Margin" user)
		(31 "F.CrtYd" user "Package Geometry/Place Bound Top")
		(29 "B.CrtYd" user "Package Geometry/Place Bound Bottom")
		(35 "F.Fab" user "Ref Des/Assembly Top")
		(33 "B.Fab" user "Ref Des/Assembly Bottom")
	)
	(footprint ""
		(layer "F.Cu")
		(at 354.27412 -98.730054 90)
		(property "Reference" "CT71"
			(at -0.53467 1.8288 0)
			(unlocked yes)
			(layer "F.SilkS")
			(effects
				(font
					(size 0.7874 0.5842)
					(thickness 0.1524)
				)
				(justify left)
			)
		)
		(property "Value" ""
			(at 0 0 90)
			(layer "F.Fab")
			(effects
				(font
					(size 1.27 1.27)
				)
			)
		)
		(duplicate_pad_numbers_are_jumpers no)
		(fp_poly
			(pts
				(xy 0.3048 -0.1016) (xy 0.3048 0.9906) (xy -0.3048 0.9906) (xy -0.3048 -0.1016)
			)
			(stroke
				(width 0)
				(type default)
			)
			(fill no)
			(layer "F.CrtYd")
		)
		(fp_line
			(start 0.3048 -0.1016)
			(end -0.3048 -0.1016)
			(stroke
				(width 0.1)
				(type default)
			)
			(layer "F.Fab")
		)
		(fp_line
			(start -0.3048 -0.1016)
			(end -0.3048 0.9906)
			(stroke
				(width 0.1)
				(type default)
			)
			(layer "F.Fab")
		)
		(fp_line
			(start 0.3048 0.9906)
			(end 0.3048 -0.1016)
			(stroke
				(width 0.1)
				(type default)
			)
			(layer "F.Fab")
		)
		(fp_line
			(start -0.3048 0.9906)
			(end 0.3048 0.9906)
			(stroke
				(width 0.1)
				(type default)
			)
			(layer "F.Fab")
		)
		(pad "1" smd rect
			(at 0 0 90)
			(size 0.508 0.508)
			(layers "F.Cu" "F.Mask" "F.Paste")
			(net "A_TSENSE_PVCCIO_CPU0")
		)
		(pad "2" smd rect
			(at 0 0.889 90)
			(size 0.508 0.508)
			(layers "F.Cu" "F.Mask" "F.Paste")
			(net "GND")
		)
		(zone
			(layer "F.Cu")
			(hatch none 0.5)
			(connect_pads
				(clearance 0)
			)
			(min_thickness 0.25)
			(keepout
				(tracks allowed)
				(vias not_allowed)
				(pads allowed)
				(copperpour not_allowed)
				(footprints allowed)
			)
			(placement
				(enabled no)
				(sheetname "")
			)
			(fill
				(thermal_gap 0.5)
				(thermal_bridge_width 0.5)
				(island_removal_mode 0)
			)
			(polygon
				(pts
					(xy 354.52812 -98.476054) (xy 354.52812 -98.984054) (xy 354.90912 -98.984054) (xy 354.90912 -98.476054)
				)
			)
		)
		(zone
			(layer "F.Cu")
			(hatch none 0.5)
			(connect_pads
				(clearance 0)
			)
			(min_thickness 0.25)
			(keepout
				(tracks not_allowed)
				(vias allowed)
				(pads allowed)
				(copperpour not_allowed)
				(footprints allowed)
			)
			(placement
				(enabled no)
				(sheetname "")
			)
			(fill
				(thermal_gap 0.5)
				(thermal_bridge_width 0.5)
				(island_removal_mode 0)
			)
			(polygon
				(pts
					(xy 354.90912 -98.476054) (xy 354.90912 -98.984054) (xy 354.52812 -98.984054) (xy 354.52812 -98.476054)
				)
			)
		)
	)
	(footprint ""
		(layer "F.Cu")
		(at 412.4452 -115.230402 90)
		(property "Reference" "R2M8"
			(at 0 0 90)
			(layer "F.SilkS")
			(hide yes)
			(effects
				(font
					(size 1.27 1.27)
				)
			)
		)
		(property "Value" ""
			(at 0 0 90)
			(layer "F.Fab")
			(effects
				(font
					(size 1.27 1.27)
				)
			)
		)
		(duplicate_pad_numbers_are_jumpers no)
		(fp_poly
			(pts
				(xy -0.2794 -0.1016) (xy 0.2794 -0.1016) (xy 0.2794 0.9906) (xy -0.2794 0.9906)
			)
			(stroke
				(width 0)
				(type default)
			)
			(fill no)
			(layer "F.CrtYd")
		)
		(fp_line
			(start 0.2794 -0.1016)
			(end -0.2794 -0.1016)
			(stroke
				(width 0.1)
				(type default)
			)
			(layer "F.Fab")
		)
		(fp_line
			(start -0.2794 -0.1016)
			(end -0.2794 0.9906)
			(stroke
				(width 0.1)
				(type default)
			)
			(layer "F.Fab")
		)
		(fp_line
			(start 0.2794 0.9906)
			(end 0.2794 -0.1016)
			(stroke
				(width 0.1)
				(type default)
			)
			(layer "F.Fab")
		)
		(fp_line
			(start -0.2794 0.9906)
			(end 0.2794 0.9906)
			(stroke
				(width 0.1)
				(type default)
			)
			(layer "F.Fab")
		)
		(pad "1" smd rect
			(at 0 0 90)
			(size 0.508 0.508)
			(layers "F.Cu" "F.Mask" "F.Paste")
			(net "P3V3_STBY")
		)
		(pad "2" smd rect
			(at 0 0.889 90)
			(size 0.508 0.508)
			(layers "F.Cu" "F.Mask" "F.Paste")
			(net "FM_CPU0_RC_ERROR_N")
		)
		(zone
			(layer "F.Cu")
			(hatch none 0.5)
			(connect_pads
				(clearance 0)
			)
			(min_thickness 0.25)
			(keepout
				(tracks allowed)
				(vias not_allowed)
				(pads allowed)
				(copperpour not_allowed)
				(footprints allowed)
			)
			(placement
				(enabled no)
				(sheetname "")
			)
			(fill
				(thermal_gap 0.5)
				(thermal_bridge_width 0.5)
				(island_removal_mode 0)
			)
			(polygon
				(pts
					(xy 412.6992 -114.976402) (xy 412.6992 -115.484402) (xy 413.0802 -115.484402) (xy 413.0802 -114.976402)
				)
			)
		)
		(zone
			(layer "F.Cu")
			(hatch none 0.5)
			(connect_pads
				(clearance 0)
			)
			(min_thickness 0.25)
			(keepout
				(tracks not_allowed)
				(vias allowed)
				(pads allowed)
				(copperpour not_allowed)
				(footprints allowed)
			)
			(placement
				(enabled no)
				(sheetname "")
			)
			(fill
				(thermal_gap 0.5)
				(thermal_bridge_width 0.5)
				(island_removal_mode 0)
			)
			(polygon
				(pts
					(xy 413.0802 -114.976402) (xy 413.0802 -115.484402) (xy 412.6992 -115.484402) (xy 412.6992 -114.976402)
				)
			)
		)
	)
	(footprint ""
		(layer "F.Cu")
		(at 24.6888 -66.6242 -90)
		(property "Reference" "R1D48"
			(at 0 0 270)
			(layer "F.SilkS")
			(hide yes)
			(effects
				(font
					(size 1.27 1.27)
				)
			)
		)
		(property "Value" ""
			(at 0 0 270)
			(layer "F.Fab")
			(effects
				(font
					(size 1.27 1.27)
				)
			)
		)
		(duplicate_pad_numbers_are_jumpers no)
		(fp_rect
			(start 0.2794 -0.1016)
			(end -0.2794 0.9906)
			(stroke
				(width 0)
				(type default)
			)
			(fill no)
			(layer "F.CrtYd")
		)
		(fp_line
			(start -0.2794 0.9906)
			(end 0.2794 0.9906)
			(stroke
				(width 0.1)
				(type default)
			)
			(layer "F.Fab")
		)
		(fp_line
			(start 0.2794 0.9906)
			(end 0.2794 -0.1016)
			(stroke
				(width 0.1)
				(type default)
			)
			(layer "F.Fab")
		)
		(fp_line
			(start -0.2794 -0.1016)
			(end -0.2794 0.9906)
			(stroke
				(width 0.1)
				(type default)
			)
			(layer "F.Fab")
		)
		(fp_line
			(start 0.2794 -0.1016)
			(end -0.2794 -0.1016)
			(stroke
				(width 0.1)
				(type default)
			)
			(layer "F.Fab")
		)
		(pad "1" smd rect
			(at 0 0 270)
			(size 0.508 0.508)
			(layers "F.Cu" "F.Mask" "F.Paste")
			(net "A_HSC_GATE")
		)
		(pad "2" smd rect
			(at 0 0.889 270)
			(size 0.508 0.508)
			(layers "F.Cu" "F.Mask" "F.Paste")
			(net "A_HSC_GATE3_R")
		)
		(zone
			(layer "F.Cu")
			(hatch none 0.5)
			(connect_pads
				(clearance 0)
			)
			(min_thickness 0.25)
			(keepout
				(tracks allowed)
				(vias not_allowed)
				(pads allowed)
				(copperpour not_allowed)
				(footprints allowed)
			)
			(placement
				(enabled no)
				(sheetname "")
			)
			(fill
				(thermal_gap 0.5)
				(thermal_bridge_width 0.5)
				(island_removal_mode 0)
			)
			(polygon
				(pts
					(xy 24.4348 -66.3702) (xy 24.4348 -66.8782) (xy 24.0538 -66.8782) (xy 24.0538 -66.3702)
				)
			)
		)
		(zone
			(layer "F.Cu")
			(hatch none 0.5)
			(connect_pads
				(clearance 0)
			)
			(min_thickness 0.25)
			(keepout
				(tracks not_allowed)
				(vias allowed)
				(pads allowed)
				(copperpour not_allowed)
				(footprints allowed)
			)
			(placement
				(enabled no)
				(sheetname "")
			)
			(fill
				(thermal_gap 0.5)
				(thermal_bridge_width 0.5)
				(island_removal_mode 0)
			)
			(polygon
				(pts
					(xy 24.4348 -66.3702) (xy 24.4348 -66.8782) (xy 24.0538 -66.8782) (xy 24.0538 -66.3702)
				)
			)
		)
	)
)
